(kicad_pcb
	(version 20260206)
	(generator "pcbnew")
	(generator_version "10.0")
	(general
		(thickness 1.6)
		(legacy_teardrops no)
	)
	(paper "A4")
	(title_block
		(title "15969-1a.1015WZS0858.brd")
		(comment 1 "Tioga Pass / footprints 283-289 of 295")
	)
	(layers
		(0 "F.Cu" signal "TOP")
		(4 "In1.Cu" signal "L2GND")
		(6 "In2.Cu" signal "L3")
		(8 "In3.Cu" signal "L4")
		(10 "In4.Cu" signal "L5GND")
		(2 "B.Cu" signal "BOTTOM")
		(9 "F.Adhes" user "F.Adhesive")
		(11 "B.Adhes" user "B.Adhesive")
		(13 "F.Paste" user "Package Geometry/Pastemask Top")
		(15 "B.Paste" user "Package Geometry/Pastemask Bottom")
		(5 "F.SilkS" user "Ref Des/Silkscreen Top")
		(7 "B.SilkS" user "Ref Des/Silkscreen Bottom")
		(1 "F.Mask" user "Board Geometry/Soldermask Top")
		(3 "B.Mask" user "Board Geometry/Soldermask Bottom")
		(17 "Dwgs.User" user "User.Drawings")
		(19 "Cmts.User" user "User.Comments")
		(21 "Eco1.User" user "User.Eco1")
		(23 "Eco2.User" user "User.Eco2")
		(25 "Edge.Cuts" user "Board Geometry/Outline")
		(27 "Margin" user)
		(31 "F.CrtYd" user "Package Geometry/Place Bound Top")
		(29 "B.CrtYd" user "Package Geometry/Place Bound Bottom")
		(35 "F.Fab" user "Ref Des/Assembly Top")
		(33 "B.Fab" user "Ref Des/Assembly Bottom")
	)
	(footprint ""
		(layer "B.Cu")
		(at 14.2748 -8.4836 180)
		(property "Reference" "PR2"
			(at 0 0 0)
			(layer "B.SilkS")
			(hide yes)
			(effects
				(font
					(size 1.27 1.27)
				)
				(justify mirror)
			)
		)
		(property "Value" "10R3F-GP"
			(at 0.0254 -2.5146 180)
			(unlocked yes)
			(layer "B.Fab")
			(hide yes)
			(effects
				(font
					(size 1.016 1.016)
					(thickness 0.1524)
				)
				(justify mirror)
			)
		)
		(property "Device Type" "R603H22"
			(at 0.0254 -4.0386 180)
			(unlocked yes)
			(layer "B.Fab")
			(hide yes)
			(effects
				(font
					(size 1.016 1.016)
					(thickness 0.1524)
				)
				(justify mirror)
			)
		)
		(duplicate_pad_numbers_are_jumpers no)
		(fp_line
			(start 0.4826 0)
			(end 0.2032 0)
			(stroke
				(width 0.2032)
				(type default)
			)
			(layer "B.SilkS")
		)
		(fp_line
			(start -0.2032 0)
			(end -0.4826 0)
			(stroke
				(width 0.2032)
				(type default)
			)
			(layer "B.SilkS")
		)
		(fp_rect
			(start 0.5842 1.3335)
			(end -0.5842 -1.3335)
			(stroke
				(width 0)
				(type default)
			)
			(fill no)
			(layer "B.CrtYd")
		)
		(fp_rect
			(start 0.5842 1.3335)
			(end -0.5842 -1.3335)
			(stroke
				(width 0)
				(type default)
			)
			(fill no)
			(layer "B.Fab")
		)
		(pad "1" smd custom
			(at 0 -0.762)
			(size 0.2159 0.2159)
			(layers "B.Cu" "B.Mask" "B.Paste")
			(net "P3V3_VR")
			(options
				(clearance outline)
				(anchor circle)
			)
			(primitives
				(gr_poly
					(pts
						(arc
							(start -0.3302 0.4318)
							(mid -0.402042 0.402042)
							(end -0.4318 0.3302)
						)
						(arc
							(start -0.4318 -0.3302)
							(mid -0.402042 -0.402042)
							(end -0.3302 -0.4318)
						)
						(arc
							(start 0.3302 -0.4318)
							(mid 0.402042 -0.402042)
							(end 0.4318 -0.3302)
						)
						(arc
							(start 0.4318 0.3302)
							(mid 0.402042 0.402042)
							(end 0.3302 0.4318)
						)
					)
					(width 0)
					(fill yes)
				)
			)
		)
		(pad "2" smd custom
			(at 0 0.762)
			(size 0.2159 0.2159)
			(layers "B.Cu" "B.Mask" "B.Paste")
			(net "P3V3_VFB_R")
			(options
				(clearance outline)
				(anchor circle)
			)
			(primitives
				(gr_poly
					(pts
						(arc
							(start -0.3302 0.4318)
							(mid -0.402042 0.402042)
							(end -0.4318 0.3302)
						)
						(arc
							(start -0.4318 -0.3302)
							(mid -0.402042 -0.402042)
							(end -0.3302 -0.4318)
						)
						(arc
							(start 0.3302 -0.4318)
							(mid 0.402042 -0.402042)
							(end 0.4318 -0.3302)
						)
						(arc
							(start 0.4318 0.3302)
							(mid 0.402042 0.402042)
							(end 0.3302 0.4318)
						)
					)
					(width 0)
					(fill yes)
				)
			)
		)
	)
	(footprint ""
		(layer "B.Cu")
		(at 16.256 -5.969)
		(property "Reference" "PG1"
			(at 0 0 0)
			(layer "B.SilkS")
			(hide yes)
			(effects
				(font
					(size 1.27 1.27)
				)
				(justify mirror)
			)
		)
		(property "Value" "COPPER-CLOSE-GP-U"
			(at -0.0762 -2.8702 0)
			(unlocked yes)
			(layer "B.Fab")
			(hide yes)
			(effects
				(font
					(size 1.016 1.016)
					(thickness 0.1524)
				)
				(justify mirror)
			)
		)
		(property "Device Type" "CON2C-U"
			(at -0.0762 -4.3942 0)
			(unlocked yes)
			(layer "B.Fab")
			(hide yes)
			(effects
				(font
					(size 1.016 1.016)
					(thickness 0.1524)
				)
				(justify mirror)
			)
		)
		(duplicate_pad_numbers_are_jumpers no)
		(fp_rect
			(start 0.9398 0.9652)
			(end -0.9398 -0.9652)
			(stroke
				(width 0)
				(type default)
			)
			(fill no)
			(layer "B.CrtYd")
		)
		(fp_rect
			(start 0.9398 0.9652)
			(end -0.9398 -0.9652)
			(stroke
				(width 0)
				(type default)
			)
			(fill no)
			(layer "B.Fab")
		)
		(pad "1" smd custom
			(at 0 -0.5334 180)
			(size 0.17145 0.17145)
			(layers "B.Cu" "B.Mask" "B.Paste")
			(net "AGND_P3V3")
			(options
				(clearance outline)
				(anchor circle)
			)
			(primitives
				(gr_poly
					(pts
						(xy -0.127 -0.3429) (xy -0.127 -0.1651) (xy -0.635 0.3429) (xy 0.635 0.3429) (xy 0.127 -0.1651)
						(xy 0.127 -0.3429)
					)
					(width 0)
					(fill yes)
				)
			)
		)
		(pad "2" smd custom
			(at 0 0.5334 180)
			(size 0.17145 0.17145)
			(layers "B.Cu" "B.Mask" "B.Paste")
			(net "GND")
			(options
				(clearance outline)
				(anchor circle)
			)
			(primitives
				(gr_poly
					(pts
						(xy -0.635 -0.3429) (xy -0.127 0.1651) (xy -0.127 0.3429) (xy 0.127 0.3429) (xy 0.127 0.1651)
						(xy 0.635 -0.3429)
					)
					(width 0)
					(fill yes)
				)
			)
		)
	)
	(footprint ""
		(layer "B.Cu")
		(at 16.1925 -13.4366 90)
		(property "Reference" "PR8"
			(at 0 0 90)
			(layer "B.SilkS")
			(hide yes)
			(effects
				(font
					(size 1.27 1.27)
				)
				(justify mirror)
			)
		)
		(property "Value" "19K6R2F-GP"
			(at -0.064008 -3.993896 90)
			(unlocked yes)
			(layer "B.Fab")
			(hide yes)
			(effects
				(font
					(size 1.016 1.016)
					(thickness 0.1524)
				)
				(justify mirror)
			)
		)
		(property "Device Type" "R402H16"
			(at -0.064008 -5.517896 90)
			(unlocked yes)
			(layer "B.Fab")
			(hide yes)
			(effects
				(font
					(size 1.016 1.016)
					(thickness 0.1524)
				)
				(justify mirror)
			)
		)
		(duplicate_pad_numbers_are_jumpers no)
		(fp_line
			(start 0.508 -0.9398)
			(end 0.508 0.9398)
			(stroke
				(width 0.1524)
				(type default)
			)
			(layer "B.SilkS")
		)
		(fp_line
			(start -0.508 -0.9398)
			(end 0.508 -0.9398)
			(stroke
				(width 0.1524)
				(type default)
			)
			(layer "B.SilkS")
		)
		(fp_rect
			(start 0.508 0.9398)
			(end -0.508 -0.9398)
			(stroke
				(width 0)
				(type default)
			)
			(fill no)
			(layer "B.CrtYd")
		)
		(fp_rect
			(start 0.508 0.9398)
			(end -0.508 -0.9398)
			(stroke
				(width 0)
				(type default)
			)
			(fill no)
			(layer "B.Fab")
		)
		(pad "1" smd custom
			(at 0 -0.4445 270)
			(size 0.1397 0.1397)
			(layers "B.Cu" "B.Mask" "B.Paste")
			(net "P12V")
			(options
				(clearance outline)
				(anchor circle)
			)
			(primitives
				(gr_poly
					(pts
						(arc
							(start -0.1778 0.2794)
							(mid -0.249642 0.249642)
							(end -0.2794 0.1778)
						)
						(arc
							(start -0.2794 -0.1778)
							(mid -0.249642 -0.249642)
							(end -0.1778 -0.2794)
						)
						(arc
							(start 0.1778 -0.2794)
							(mid 0.249642 -0.249642)
							(end 0.2794 -0.1778)
						)
						(arc
							(start 0.2794 0.1778)
							(mid 0.249642 0.249642)
							(end 0.1778 0.2794)
						)
					)
					(width 0)
					(fill yes)
				)
			)
		)
		(pad "2" smd custom
			(at 0 0.4445 270)
			(size 0.1397 0.1397)
			(layers "B.Cu" "B.Mask" "B.Paste")
			(net "P3V3_EN")
			(options
				(clearance outline)
				(anchor circle)
			)
			(primitives
				(gr_poly
					(pts
						(arc
							(start -0.1778 0.2794)
							(mid -0.249642 0.249642)
							(end -0.2794 0.1778)
						)
						(arc
							(start -0.2794 -0.1778)
							(mid -0.249642 -0.249642)
							(end -0.1778 -0.2794)
						)
						(arc
							(start 0.1778 -0.2794)
							(mid 0.249642 -0.249642)
							(end 0.2794 -0.1778)
						)
						(arc
							(start 0.2794 0.1778)
							(mid 0.249642 0.249642)
							(end 0.1778 0.2794)
						)
					)
					(width 0)
					(fill yes)
				)
			)
		)
	)
	(footprint ""
		(layer "B.Cu")
		(at 34.29 -1.0922 -90)
		(property "Reference" "C18"
			(at 0 0 90)
			(layer "B.SilkS")
			(hide yes)
			(effects
				(font
					(size 1.27 1.27)
				)
				(justify mirror)
			)
		)
		(property "Value" "SCD1U16V2KX-3GP"
			(at -1.1811 -2.7051 270)
			(unlocked yes)
			(layer "B.Fab")
			(hide yes)
			(effects
				(font
					(size 1.016 1.016)
					(thickness 0.1524)
				)
				(justify mirror)
			)
		)
		(property "Device Type" "C402H22"
			(at -1.1811 -4.2291 270)
			(unlocked yes)
			(layer "B.Fab")
			(hide yes)
			(effects
				(font
					(size 1.016 1.016)
					(thickness 0.1524)
				)
				(justify mirror)
			)
		)
		(duplicate_pad_numbers_are_jumpers no)
		(fp_rect
			(start 0.4318 0.9525)
			(end -0.4318 -0.9525)
			(stroke
				(width 0)
				(type default)
			)
			(fill no)
			(layer "B.CrtYd")
		)
		(fp_rect
			(start 0.4318 0.9525)
			(end -0.4318 -0.9525)
			(stroke
				(width 0)
				(type default)
			)
			(fill no)
			(layer "B.Fab")
		)
		(pad "1" smd custom
			(at 0 -0.4445 90)
			(size 0.1524 0.1524)
			(layers "B.Cu" "B.Mask" "B.Paste")
			(net "P3V3")
			(options
				(clearance outline)
				(anchor circle)
			)
			(primitives
				(gr_poly
					(pts
						(arc
							(start 0.3048 0.2032)
							(mid 0.275042 0.275042)
							(end 0.2032 0.3048)
						)
						(arc
							(start -0.2032 0.3048)
							(mid -0.275042 0.275042)
							(end -0.3048 0.2032)
						)
						(arc
							(start -0.3048 -0.2032)
							(mid -0.275042 -0.275042)
							(end -0.2032 -0.3048)
						)
						(arc
							(start 0.2032 -0.3048)
							(mid 0.275042 -0.275042)
							(end 0.3048 -0.2032)
						)
					)
					(width 0)
					(fill yes)
				)
			)
		)
		(pad "2" smd custom
			(at 0 0.4445 90)
			(size 0.1524 0.1524)
			(layers "B.Cu" "B.Mask" "B.Paste")
			(net "GND")
			(options
				(clearance outline)
				(anchor circle)
			)
			(primitives
				(gr_poly
					(pts
						(arc
							(start 0.3048 0.2032)
							(mid 0.275042 0.275042)
							(end 0.2032 0.3048)
						)
						(arc
							(start -0.2032 0.3048)
							(mid -0.275042 0.275042)
							(end -0.3048 0.2032)
						)
						(arc
							(start -0.3048 -0.2032)
							(mid -0.275042 -0.275042)
							(end -0.2032 -0.3048)
						)
						(arc
							(start 0.2032 -0.3048)
							(mid 0.275042 -0.275042)
							(end 0.3048 -0.2032)
						)
					)
					(width 0)
					(fill yes)
				)
			)
		)
	)
	(footprint ""
		(layer "B.Cu")
		(at 130.0988 -24.9936 180)
		(property "Reference" "R168"
			(at 0 0 0)
			(layer "B.SilkS")
			(hide yes)
			(effects
				(font
					(size 1.27 1.27)
				)
				(justify mirror)
			)
		)
		(property "Value" "0R2F-1-GP"
			(at -0.064008 -3.993896 180)
			(unlocked yes)
			(layer "B.Fab")
			(hide yes)
			(effects
				(font
					(size 1.016 1.016)
					(thickness 0.1524)
				)
				(justify mirror)
			)
		)
		(property "Device Type" "R402H16"
			(at -0.064008 -5.517896 180)
			(unlocked yes)
			(layer "B.Fab")
			(hide yes)
			(effects
				(font
					(size 1.016 1.016)
					(thickness 0.1524)
				)
				(justify mirror)
			)
		)
		(duplicate_pad_numbers_are_jumpers no)
		(fp_line
			(start 0.508 -0.9398)
			(end 0.508 0.9398)
			(stroke
				(width 0.1524)
				(type default)
			)
			(layer "B.SilkS")
		)
		(fp_line
			(start -0.508 -0.9398)
			(end 0.508 -0.9398)
			(stroke
				(width 0.1524)
				(type default)
			)
			(layer "B.SilkS")
		)
		(fp_rect
			(start 0.508 0.9398)
			(end -0.508 -0.9398)
			(stroke
				(width 0)
				(type default)
			)
			(fill no)
			(layer "B.CrtYd")
		)
		(fp_rect
			(start 0.508 0.9398)
			(end -0.508 -0.9398)
			(stroke
				(width 0)
				(type default)
			)
			(fill no)
			(layer "B.Fab")
		)
		(pad "1" smd custom
			(at 0 -0.4445)
			(size 0.1397 0.1397)
			(layers "B.Cu" "B.Mask" "B.Paste")
			(net "SMCLK_USB_HUB")
			(options
				(clearance outline)
				(anchor circle)
			)
			(primitives
				(gr_poly
					(pts
						(arc
							(start -0.1778 0.2794)
							(mid -0.249642 0.249642)
							(end -0.2794 0.1778)
						)
						(arc
							(start -0.2794 -0.1778)
							(mid -0.249642 -0.249642)
							(end -0.1778 -0.2794)
						)
						(arc
							(start 0.1778 -0.2794)
							(mid 0.249642 -0.249642)
							(end 0.2794 -0.1778)
						)
						(arc
							(start 0.2794 0.1778)
							(mid 0.249642 0.249642)
							(end 0.1778 0.2794)
						)
					)
					(width 0)
					(fill yes)
				)
			)
		)
		(pad "2" smd custom
			(at 0 0.4445)
			(size 0.1397 0.1397)
			(layers "B.Cu" "B.Mask" "B.Paste")
			(net "SMCLK_PCH_DEVICE")
			(options
				(clearance outline)
				(anchor circle)
			)
			(primitives
				(gr_poly
					(pts
						(arc
							(start -0.1778 0.2794)
							(mid -0.249642 0.249642)
							(end -0.2794 0.1778)
						)
						(arc
							(start -0.2794 -0.1778)
							(mid -0.249642 -0.249642)
							(end -0.1778 -0.2794)
						)
						(arc
							(start 0.1778 -0.2794)
							(mid 0.249642 -0.249642)
							(end 0.2794 -0.1778)
						)
						(arc
							(start 0.2794 0.1778)
							(mid 0.249642 0.249642)
							(end 0.1778 0.2794)
						)
					)
					(width 0)
					(fill yes)
				)
			)
		)
	)
	(footprint ""
		(layer "B.Cu")
		(at 26.7208 -22.1742 90)
		(property "Reference" "R173"
			(at 0 0 90)
			(layer "B.SilkS")
			(hide yes)
			(effects
				(font
					(size 1.27 1.27)
				)
				(justify mirror)
			)
		)
		(property "Value" "0R2F-1-GP"
			(at -0.064008 -3.993896 90)
			(unlocked yes)
			(layer "B.Fab")
			(hide yes)
			(effects
				(font
					(size 1.016 1.016)
					(thickness 0.1524)
				)
				(justify mirror)
			)
		)
		(property "Device Type" "R402H16"
			(at -0.064008 -5.517896 90)
			(unlocked yes)
			(layer "B.Fab")
			(hide yes)
			(effects
				(font
					(size 1.016 1.016)
					(thickness 0.1524)
				)
				(justify mirror)
			)
		)
		(duplicate_pad_numbers_are_jumpers no)
		(fp_line
			(start 0.508 -0.9398)
			(end 0.508 0.9398)
			(stroke
				(width 0.1524)
				(type default)
			)
			(layer "B.SilkS")
		)
		(fp_line
			(start -0.508 -0.9398)
			(end 0.508 -0.9398)
			(stroke
				(width 0.1524)
				(type default)
			)
			(layer "B.SilkS")
		)
		(fp_rect
			(start 0.508 0.9398)
			(end -0.508 -0.9398)
			(stroke
				(width 0)
				(type default)
			)
			(fill no)
			(layer "B.CrtYd")
		)
		(fp_rect
			(start 0.508 0.9398)
			(end -0.508 -0.9398)
			(stroke
				(width 0)
				(type default)
			)
			(fill no)
			(layer "B.Fab")
		)
		(pad "1" smd custom
			(at 0 -0.4445 270)
			(size 0.1397 0.1397)
			(layers "B.Cu" "B.Mask" "B.Paste")
			(net "SMB_VMONITOR_ATX_ALERT_N")
			(options
				(clearance outline)
				(anchor circle)
			)
			(primitives
				(gr_poly
					(pts
						(arc
							(start -0.1778 0.2794)
							(mid -0.249642 0.249642)
							(end -0.2794 0.1778)
						)
						(arc
							(start -0.2794 -0.1778)
							(mid -0.249642 -0.249642)
							(end -0.1778 -0.2794)
						)
						(arc
							(start 0.1778 -0.2794)
							(mid 0.249642 -0.249642)
							(end 0.2794 -0.1778)
						)
						(arc
							(start 0.2794 0.1778)
							(mid 0.249642 0.249642)
							(end 0.1778 0.2794)
						)
					)
					(width 0)
					(fill yes)
				)
			)
		)
		(pad "2" smd custom
			(at 0 0.4445 270)
			(size 0.1397 0.1397)
			(layers "B.Cu" "B.Mask" "B.Paste")
			(net "SMB_BMC_DEVICE_ALERT_N")
			(options
				(clearance outline)
				(anchor circle)
			)
			(primitives
				(gr_poly
					(pts
						(arc
							(start -0.1778 0.2794)
							(mid -0.249642 0.249642)
							(end -0.2794 0.1778)
						)
						(arc
							(start -0.2794 -0.1778)
							(mid -0.249642 -0.249642)
							(end -0.1778 -0.2794)
						)
						(arc
							(start 0.1778 -0.2794)
							(mid 0.249642 -0.249642)
							(end 0.2794 -0.1778)
						)
						(arc
							(start 0.2794 0.1778)
							(mid 0.249642 0.249642)
							(end 0.1778 0.2794)
						)
					)
					(width 0)
					(fill yes)
				)
			)
		)
	)
	(footprint ""
		(layer "B.Cu")
		(at 23.0632 -1.0668)
		(property "Reference" "PL2"
			(at 0 0 0)
			(layer "B.SilkS")
			(hide yes)
			(effects
				(font
					(size 1.27 1.27)
				)
				(justify mirror)
			)
		)
		(property "Value" "COIL-1D5UH-47-GP"
			(at 5.6134 -2.4892 0)
			(unlocked yes)
			(layer "B.Fab")
			(hide yes)
			(effects
				(font
					(size 1.016 1.016)
					(thickness 0.1524)
				)
				(justify mirror)
			)
		)
		(property "Device Type" "L7166-1830-UH197"
			(at 5.6134 -4.0132 0)
			(unlocked yes)
			(layer "B.Fab")
			(hide yes)
			(effects
				(font
					(size 1.016 1.016)
					(thickness 0.1524)
				)
				(justify mirror)
			)
		)
		(duplicate_pad_numbers_are_jumpers no)
		(fp_line
			(start -3.556 -4.5466)
			(end -3.556 4.5466)
			(stroke
				(width 0.1524)
				(type default)
			)
			(layer "B.SilkS")
		)
		(fp_line
			(start -3.556 4.5466)
			(end 3.556 4.5466)
			(stroke
				(width 0.1524)
				(type default)
			)
			(layer "B.SilkS")
		)
		(fp_line
			(start 3.556 -4.5466)
			(end -3.556 -4.5466)
			(stroke
				(width 0.1524)
				(type default)
			)
			(layer "B.SilkS")
		)
		(fp_line
			(start 3.556 4.5466)
			(end 3.556 -4.5466)
			(stroke
				(width 0.1524)
				(type default)
			)
			(layer "B.SilkS")
		)
		(fp_rect
			(start 3.302 3.5306)
			(end -3.302 -3.5306)
			(stroke
				(width 0)
				(type default)
			)
			(fill no)
			(layer "B.CrtYd")
		)
		(fp_poly
			(pts
				(xy 3.81 4.6228) (xy 3.81 -2.3241) (xy 3.302 -2.3241) (xy 3.302 3.5306) (xy -3.302 3.5306) (xy -3.302 -3.5306)
				(xy 3.302 -3.5306) (xy 3.302 -2.3368) (xy 3.81 -2.3368) (xy 3.81 -4.6228) (xy -3.81 -4.6228) (xy -3.81 4.6228)
			)
			(stroke
				(width 0)
				(type default)
			)
			(fill no)
			(layer "B.CrtYd")
		)
		(fp_rect
			(start 3.81 4.6228)
			(end -3.81 -4.6228)
			(stroke
				(width 0)
				(type default)
			)
			(fill no)
			(layer "B.Fab")
		)
		(pad "1" smd rect
			(at 0 -2.804922 180)
			(size 3.5052 2.9718)
			(layers "B.Cu" "B.Mask" "B.Paste")
			(net "P3V3_SW")
		)
		(pad "2" smd rect
			(at 0 2.804922 180)
			(size 3.5052 2.9718)
			(layers "B.Cu" "B.Mask" "B.Paste")
			(net "P3V3_VR")
		)
	)
)
